# T6G (Grand Teton) — schematic netlist excerpt (pin names and nets, part order shuffled) for the footprints in the layout excerpt that follows; sources: Cadence DE-HDL packaged netlist, KiCad conversion of 04192023_DAF0TMB3IC0_F0TG_MB_C_brd_V02_OCP.brd

PR339  Q_RES  1K 1% CHIP  pkg 0402LF  page 215 : A = PVDDCR_SOC_P1 ; B = GND
C6118  Q_CAP  10UF 25V 10% X6S  pkg C0805  page 179 : A = P1V2_CPU0_USB2_DVDD12 ; B = GND
C2388  Q_CAP  22UF 4V 20% X6S  pkg C0402  page 73 : A = PVDDCR_CPU1_P1 ; B = GND

(kicad_pcb
	(version 20260206)
	(generator "pcbnew")
	(generator_version "10.0")
	(general
		(thickness 1.6)
		(legacy_teardrops no)
	)
	(paper "A4")
	(title_block
		(title "04192023_DAF0TMB3IC0_F0TG_MB_C_brd_V02_OCP.brd")
		(comment 1 "Grand Teton / footprints 6374-6376 of 8354")
	)
	(layers
		(0 "F.Cu" signal "TOP")
		(4 "In1.Cu" signal "GND")
		(6 "In2.Cu" signal "IN1")
		(8 "In3.Cu" signal "GND1")
		(10 "In4.Cu" signal "IN2")
		(12 "In5.Cu" signal "GND2")
		(14 "In6.Cu" signal "IN3")
		(16 "In7.Cu" signal "GND3")
		(18 "In8.Cu" signal "VCC")
		(20 "In9.Cu" signal "VCC1")
		(22 "In10.Cu" signal "GND4")
		(24 "In11.Cu" signal "IN4")
		(26 "In12.Cu" signal "GND5")
		(28 "In13.Cu" signal "IN5")
		(30 "In14.Cu" signal "GND6")
		(32 "In15.Cu" signal "IN6")
		(34 "In16.Cu" signal "GND7")
		(2 "B.Cu" signal "BOTTOM")
		(9 "F.Adhes" user "F.Adhesive")
		(11 "B.Adhes" user "B.Adhesive")
		(13 "F.Paste" user "Package Geometry/Pastemask Top")
		(15 "B.Paste" user "Package Geometry/Pastemask Bottom")
		(5 "F.SilkS" user "Ref Des/Silkscreen Top")
		(7 "B.SilkS" user "Ref Des/Silkscreen Bottom")
		(1 "F.Mask" user "Board Geometry/Soldermask Top")
		(3 "B.Mask" user "Board Geometry/Soldermask Bottom")
		(17 "Dwgs.User" user "User.Drawings")
		(19 "Cmts.User" user "User.Comments")
		(21 "Eco1.User" user "User.Eco1")
		(23 "Eco2.User" user "User.Eco2")
		(25 "Edge.Cuts" user "Board Geometry/Outline")
		(27 "Margin" user)
		(31 "F.CrtYd" user "Package Geometry/Place Bound Top")
		(29 "B.CrtYd" user "Package Geometry/Place Bound Bottom")
		(35 "F.Fab" user "Ref Des/Assembly Top")
		(33 "B.Fab" user "Ref Des/Assembly Bottom")
	)
	(footprint ""
		(layer "B.Cu")
		(at 114.033046 -267.529564)
		(property "Reference" "C2388"
			(at 0 0 0)
			(layer "B.SilkS")
			(hide yes)
			(effects
				(font
					(size 1.27 1.27)
				)
				(justify mirror)
			)
		)
		(property "Value" ""
			(at 0 0 0)
			(layer "B.Fab")
			(effects
				(font
					(size 1.27 1.27)
				)
				(justify mirror)
			)
		)
		(duplicate_pad_numbers_are_jumpers no)
		(fp_line
			(start -0.7874 -0.4064)
			(end -0.7874 0.4064)
			(stroke
				(width 0.1524)
				(type default)
			)
			(layer "B.SilkS")
		)
		(fp_line
			(start -0.7874 0.4064)
			(end 0.7874 0.4064)
			(stroke
				(width 0.1524)
				(type default)
			)
			(layer "B.SilkS")
		)
		(fp_line
			(start 0.7874 -0.4064)
			(end -0.7874 -0.4064)
			(stroke
				(width 0.1524)
				(type default)
			)
			(layer "B.SilkS")
		)
		(fp_line
			(start 0.7874 0.4064)
			(end 0.7874 -0.4064)
			(stroke
				(width 0.1524)
				(type default)
			)
			(layer "B.SilkS")
		)
		(fp_line
			(start -0.67945 -0.3048)
			(end -0.67945 0.3048)
			(stroke
				(width 0.1)
				(type default)
			)
			(layer "B.Fab")
		)
		(fp_line
			(start -0.67945 0.3048)
			(end -0.120396 0.3048)
			(stroke
				(width 0.1)
				(type default)
			)
			(layer "B.Fab")
		)
		(fp_line
			(start -0.12065 -0.3048)
			(end -0.67945 -0.3048)
			(stroke
				(width 0.1)
				(type default)
			)
			(layer "B.Fab")
		)
		(fp_line
			(start -0.12065 -0.2794)
			(end -0.12065 -0.3048)
			(stroke
				(width 0.1)
				(type default)
			)
			(layer "B.Fab")
		)
		(fp_line
			(start -0.120396 0.2794)
			(end 0.12065 0.2794)
			(stroke
				(width 0.1)
				(type default)
			)
			(layer "B.Fab")
		)
		(fp_line
			(start -0.120396 0.3048)
			(end -0.120396 0.2794)
			(stroke
				(width 0.1)
				(type default)
			)
			(layer "B.Fab")
		)
		(fp_line
			(start 0.12065 -0.305054)
			(end 0.12065 -0.2794)
			(stroke
				(width 0.1)
				(type default)
			)
			(layer "B.Fab")
		)
		(fp_line
			(start 0.12065 -0.2794)
			(end -0.12065 -0.2794)
			(stroke
				(width 0.1)
				(type default)
			)
			(layer "B.Fab")
		)
		(fp_line
			(start 0.12065 0.2794)
			(end 0.12065 0.3048)
			(stroke
				(width 0.1)
				(type default)
			)
			(layer "B.Fab")
		)
		(fp_line
			(start 0.12065 0.3048)
			(end 0.67945 0.3048)
			(stroke
				(width 0.1)
				(type default)
			)
			(layer "B.Fab")
		)
		(fp_line
			(start 0.67945 -0.305054)
			(end 0.12065 -0.305054)
			(stroke
				(width 0.1)
				(type default)
			)
			(layer "B.Fab")
		)
		(fp_line
			(start 0.67945 0.3048)
			(end 0.67945 -0.305054)
			(stroke
				(width 0.1)
				(type default)
			)
			(layer "B.Fab")
		)
		(pad "1" smd circle
			(at 0.40005 0 180)
			(size 0 0)
			(layers "B.Cu" "B.Mask" "B.Paste")
			(net "PVDDCR_CPU1_P1")
		)
		(pad "2" smd circle
			(at -0.40005 0 180)
			(size 0 0)
			(layers "B.Cu" "B.Mask" "B.Paste")
			(net "GND")
		)
	)
	(footprint ""
		(layer "B.Cu")
		(at 115.595146 -30.481778)
		(property "Reference" "C6118"
			(at 0 0 0)
			(layer "B.SilkS")
			(hide yes)
			(effects
				(font
					(size 1.27 1.27)
				)
				(justify mirror)
			)
		)
		(property "Value" ""
			(at 0 0 0)
			(layer "B.Fab")
			(effects
				(font
					(size 1.27 1.27)
				)
				(justify mirror)
			)
		)
		(duplicate_pad_numbers_are_jumpers no)
		(fp_line
			(start -1.524 -0.762)
			(end -1.524 0.762)
			(stroke
				(width 0.1524)
				(type default)
			)
			(layer "B.SilkS")
		)
		(fp_line
			(start -1.524 0.762)
			(end 1.524 0.762)
			(stroke
				(width 0.1524)
				(type default)
			)
			(layer "B.SilkS")
		)
		(fp_line
			(start 1.524 -0.762)
			(end -1.524 -0.762)
			(stroke
				(width 0.1524)
				(type default)
			)
			(layer "B.SilkS")
		)
		(fp_line
			(start 1.524 0.762)
			(end 1.524 -0.762)
			(stroke
				(width 0.1524)
				(type default)
			)
			(layer "B.SilkS")
		)
		(fp_line
			(start -1.1049 -0.724916)
			(end 1.1049 -0.724916)
			(stroke
				(width 0.1)
				(type default)
			)
			(layer "B.Fab")
		)
		(fp_line
			(start -1.1049 0.724916)
			(end -1.1049 -0.724916)
			(stroke
				(width 0.1)
				(type default)
			)
			(layer "B.Fab")
		)
		(fp_line
			(start 1.1049 -0.724916)
			(end 1.1049 0.724916)
			(stroke
				(width 0.1)
				(type default)
			)
			(layer "B.Fab")
		)
		(fp_line
			(start 1.1049 0.724916)
			(end -1.1049 0.724916)
			(stroke
				(width 0.1)
				(type default)
			)
			(layer "B.Fab")
		)
		(pad "1" smd rect
			(at 0.889 0)
			(size 1.016 1.27)
			(layers "B.Cu" "B.Mask" "B.Paste")
			(net "P1V2_CPU0_USB2_DVDD12")
		)
		(pad "2" smd rect
			(at -0.889 0)
			(size 1.016 1.27)
			(layers "B.Cu" "B.Mask" "B.Paste")
			(net "GND")
		)
	)
	(footprint ""
		(layer "B.Cu")
		(at 138.341354 -164.957252 90)
		(property "Reference" "PR339"
			(at 0 0 90)
			(layer "B.SilkS")
			(hide yes)
			(effects
				(font
					(size 1.27 1.27)
				)
				(justify mirror)
			)
		)
		(property "Value" ""
			(at 0 0 90)
			(layer "B.Fab")
			(effects
				(font
					(size 1.27 1.27)
				)
				(justify mirror)
			)
		)
		(duplicate_pad_numbers_are_jumpers no)
		(fp_line
			(start 0.7874 -0.4064)
			(end -0.7874 -0.4064)
			(stroke
				(width 0.1524)
				(type default)
			)
			(layer "B.SilkS")
		)
		(fp_line
			(start -0.7874 -0.4064)
			(end -0.7874 0.4064)
			(stroke
				(width 0.1524)
				(type default)
			)
			(layer "B.SilkS")
		)
		(fp_line
			(start 0.7874 0.4064)
			(end 0.7874 -0.4064)
			(stroke
				(width 0.1524)
				(type default)
			)
			(layer "B.SilkS")
		)
		(fp_line
			(start -0.7874 0.4064)
			(end 0.7874 0.4064)
			(stroke
				(width 0.1524)
				(type default)
			)
			(layer "B.SilkS")
		)
		(fp_line
			(start 0.67945 -0.305054)
			(end 0.12065 -0.305054)
			(stroke
				(width 0.1)
				(type default)
			)
			(layer "B.Fab")
		)
		(fp_line
			(start 0.12065 -0.305054)
			(end 0.12065 -0.2794)
			(stroke
				(width 0.1)
				(type default)
			)
			(layer "B.Fab")
		)
		(fp_line
			(start -0.12065 -0.3048)
			(end -0.67945 -0.3048)
			(stroke
				(width 0.1)
				(type default)
			)
			(layer "B.Fab")
		)
		(fp_line
			(start -0.67945 -0.3048)
			(end -0.67945 0.3048)
			(stroke
				(width 0.1)
				(type default)
			)
			(layer "B.Fab")
		)
		(fp_line
			(start 0.12065 -0.2794)
			(end -0.12065 -0.2794)
			(stroke
				(width 0.1)
				(type default)
			)
			(layer "B.Fab")
		)
		(fp_line
			(start -0.12065 -0.2794)
			(end -0.12065 -0.3048)
			(stroke
				(width 0.1)
				(type default)
			)
			(layer "B.Fab")
		)
		(fp_line
			(start 0.12065 0.2794)
			(end 0.12065 0.3048)
			(stroke
				(width 0.1)
				(type default)
			)
			(layer "B.Fab")
		)
		(fp_line
			(start -0.120396 0.2794)
			(end 0.12065 0.2794)
			(stroke
				(width 0.1)
				(type default)
			)
			(layer "B.Fab")
		)
		(fp_line
			(start 0.67945 0.3048)
			(end 0.67945 -0.305054)
			(stroke
				(width 0.1)
				(type default)
			)
			(layer "B.Fab")
		)
		(fp_line
			(start 0.12065 0.3048)
			(end 0.67945 0.3048)
			(stroke
				(width 0.1)
				(type default)
			)
			(layer "B.Fab")
		)
		(fp_line
			(start -0.120396 0.3048)
			(end -0.120396 0.2794)
			(stroke
				(width 0.1)
				(type default)
			)
			(layer "B.Fab")
		)
		(fp_line
			(start -0.67945 0.3048)
			(end -0.120396 0.3048)
			(stroke
				(width 0.1)
				(type default)
			)
			(layer "B.Fab")
		)
		(pad "1" smd circle
			(at 0.40005 0 270)
			(size 0 0)
			(layers "B.Cu" "B.Mask" "B.Paste")
			(net "PVDDCR_SOC_P1")
		)
		(pad "2" smd circle
			(at -0.40005 0 270)
			(size 0 0)
			(layers "B.Cu" "B.Mask" "B.Paste")
			(net "GND")
		)
	)
)
